# S9S_MB_2U (Grand Teton) — schematic netlist excerpt (pin names and nets, part order shuffled) for the footprints in the layout excerpt that follows; sources: Cadence DE-HDL packaged netlist, KiCad conversion of 03242023_DA0F0TMBIJ0_F0T_Motherboard_J_brd_V01_OCP.brd

C1559  Q_CAP_DIFFBUS  DIFF BUS_0.22UF 6.3V 20% X6S  pkg C0201  page 175 : \1\ = P5E_CPU0_PE4_TX_C_DP<10> ; \2\ = P5E_CPU0_PE4_TX_DP<10>
R718  Q_RES  1K 1% CHIP  pkg 0402LF  page 243 : A = MB_FRU_ADDR1 ; B = GND
R4711  Q_RES  249 1% CHIP  pkg 0402LF  page 255 : A = LED_P12V_SCM_FAULT ; B = P3V3_AUX

(kicad_pcb
	(version 20260206)
	(generator "pcbnew")
	(generator_version "10.0")
	(general
		(thickness 1.6)
		(legacy_teardrops no)
	)
	(paper "A4")
	(title_block
		(title "03242023_DA0F0TMBIJ0_F0T_Motherboard_J_brd_V01_OCP.brd")
		(comment 1 "Grand Teton / footprints 973-975 of 6105")
	)
	(layers
		(0 "F.Cu" signal "TOP")
		(4 "In1.Cu" signal "GND")
		(6 "In2.Cu" signal "IN1")
		(8 "In3.Cu" signal "GND1")
		(10 "In4.Cu" signal "IN2")
		(12 "In5.Cu" signal "GND2")
		(14 "In6.Cu" signal "IN3")
		(16 "In7.Cu" signal "GND3")
		(18 "In8.Cu" signal "VCC")
		(20 "In9.Cu" signal "VCC1")
		(22 "In10.Cu" signal "GND4")
		(24 "In11.Cu" signal "IN4")
		(26 "In12.Cu" signal "GND5")
		(28 "In13.Cu" signal "IN5")
		(30 "In14.Cu" signal "GND6")
		(32 "In15.Cu" signal "IN6")
		(34 "In16.Cu" signal "GND7")
		(2 "B.Cu" signal "BOTTOM")
		(9 "F.Adhes" user "F.Adhesive")
		(11 "B.Adhes" user "B.Adhesive")
		(13 "F.Paste" user "Package Geometry/Pastemask Top")
		(15 "B.Paste" user "Package Geometry/Pastemask Bottom")
		(5 "F.SilkS" user "Ref Des/Silkscreen Top")
		(7 "B.SilkS" user "Ref Des/Silkscreen Bottom")
		(1 "F.Mask" user "Board Geometry/Soldermask Top")
		(3 "B.Mask" user "Board Geometry/Soldermask Bottom")
		(17 "Dwgs.User" user "User.Drawings")
		(19 "Cmts.User" user "User.Comments")
		(21 "Eco1.User" user "User.Eco1")
		(23 "Eco2.User" user "User.Eco2")
		(25 "Edge.Cuts" user "Board Geometry/Outline")
		(27 "Margin" user)
		(31 "F.CrtYd" user "Package Geometry/Place Bound Top")
		(29 "B.CrtYd" user "Package Geometry/Place Bound Bottom")
		(35 "F.Fab" user "Ref Des/Assembly Top")
		(33 "B.Fab" user "Ref Des/Assembly Bottom")
	)
	(footprint ""
		(layer "F.Cu")
		(at 204.333348 -68.5292)
		(property "Reference" "R4711"
			(at 0 0 0)
			(layer "F.SilkS")
			(hide yes)
			(effects
				(font
					(size 1.27 1.27)
				)
			)
		)
		(property "Value" ""
			(at 0 0 0)
			(layer "F.Fab")
			(effects
				(font
					(size 1.27 1.27)
				)
			)
		)
		(duplicate_pad_numbers_are_jumpers no)
		(fp_line
			(start -0.7874 -0.4064)
			(end 0.7874 -0.4064)
			(stroke
				(width 0.1524)
				(type default)
			)
			(layer "F.SilkS")
		)
		(fp_line
			(start -0.7874 0.4064)
			(end -0.7874 -0.4064)
			(stroke
				(width 0.1524)
				(type default)
			)
			(layer "F.SilkS")
		)
		(fp_line
			(start 0.7874 -0.4064)
			(end 0.7874 0.4064)
			(stroke
				(width 0.1524)
				(type default)
			)
			(layer "F.SilkS")
		)
		(fp_line
			(start 0.7874 0.4064)
			(end -0.7874 0.4064)
			(stroke
				(width 0.1524)
				(type default)
			)
			(layer "F.SilkS")
		)
		(fp_line
			(start -0.67945 -0.305054)
			(end -0.12065 -0.305054)
			(stroke
				(width 0.1)
				(type default)
			)
			(layer "F.Fab")
		)
		(fp_line
			(start -0.67945 0.3048)
			(end -0.67945 -0.305054)
			(stroke
				(width 0.1)
				(type default)
			)
			(layer "F.Fab")
		)
		(fp_line
			(start -0.12065 -0.305054)
			(end -0.12065 -0.2794)
			(stroke
				(width 0.1)
				(type default)
			)
			(layer "F.Fab")
		)
		(fp_line
			(start -0.12065 -0.2794)
			(end 0.12065 -0.2794)
			(stroke
				(width 0.1)
				(type default)
			)
			(layer "F.Fab")
		)
		(fp_line
			(start -0.12065 0.2794)
			(end -0.12065 0.3048)
			(stroke
				(width 0.1)
				(type default)
			)
			(layer "F.Fab")
		)
		(fp_line
			(start -0.12065 0.3048)
			(end -0.67945 0.3048)
			(stroke
				(width 0.1)
				(type default)
			)
			(layer "F.Fab")
		)
		(fp_line
			(start 0.120396 0.2794)
			(end -0.12065 0.2794)
			(stroke
				(width 0.1)
				(type default)
			)
			(layer "F.Fab")
		)
		(fp_line
			(start 0.120396 0.3048)
			(end 0.120396 0.2794)
			(stroke
				(width 0.1)
				(type default)
			)
			(layer "F.Fab")
		)
		(fp_line
			(start 0.12065 -0.3048)
			(end 0.67945 -0.3048)
			(stroke
				(width 0.1)
				(type default)
			)
			(layer "F.Fab")
		)
		(fp_line
			(start 0.12065 -0.2794)
			(end 0.12065 -0.3048)
			(stroke
				(width 0.1)
				(type default)
			)
			(layer "F.Fab")
		)
		(fp_line
			(start 0.67945 -0.3048)
			(end 0.67945 0.3048)
			(stroke
				(width 0.1)
				(type default)
			)
			(layer "F.Fab")
		)
		(fp_line
			(start 0.67945 0.3048)
			(end 0.120396 0.3048)
			(stroke
				(width 0.1)
				(type default)
			)
			(layer "F.Fab")
		)
		(pad "1" smd circle
			(at -0.40005 0)
			(size 0 0)
			(layers "F.Cu" "F.Mask" "F.Paste")
			(net "LED_P12V_SCM_FAULT")
		)
		(pad "2" smd circle
			(at 0.40005 0)
			(size 0 0)
			(layers "F.Cu" "F.Mask" "F.Paste")
			(net "P3V3_AUX")
		)
	)
	(footprint ""
		(layer "F.Cu")
		(at 274.7137 -95.029274 180)
		(property "Reference" "R718"
			(at 0 0 180)
			(layer "F.SilkS")
			(hide yes)
			(effects
				(font
					(size 1.27 1.27)
				)
			)
		)
		(property "Value" ""
			(at 0 0 180)
			(layer "F.Fab")
			(effects
				(font
					(size 1.27 1.27)
				)
			)
		)
		(duplicate_pad_numbers_are_jumpers no)
		(fp_line
			(start 0.7874 0.4064)
			(end -0.7874 0.4064)
			(stroke
				(width 0.1524)
				(type default)
			)
			(layer "F.SilkS")
		)
		(fp_line
			(start 0.7874 -0.4064)
			(end 0.7874 0.4064)
			(stroke
				(width 0.1524)
				(type default)
			)
			(layer "F.SilkS")
		)
		(fp_line
			(start -0.7874 0.4064)
			(end -0.7874 -0.4064)
			(stroke
				(width 0.1524)
				(type default)
			)
			(layer "F.SilkS")
		)
		(fp_line
			(start -0.7874 -0.4064)
			(end 0.7874 -0.4064)
			(stroke
				(width 0.1524)
				(type default)
			)
			(layer "F.SilkS")
		)
		(fp_line
			(start 0.67945 0.3048)
			(end 0.120396 0.3048)
			(stroke
				(width 0.1)
				(type default)
			)
			(layer "F.Fab")
		)
		(fp_line
			(start 0.67945 -0.3048)
			(end 0.67945 0.3048)
			(stroke
				(width 0.1)
				(type default)
			)
			(layer "F.Fab")
		)
		(fp_line
			(start 0.12065 -0.2794)
			(end 0.12065 -0.3048)
			(stroke
				(width 0.1)
				(type default)
			)
			(layer "F.Fab")
		)
		(fp_line
			(start 0.12065 -0.3048)
			(end 0.67945 -0.3048)
			(stroke
				(width 0.1)
				(type default)
			)
			(layer "F.Fab")
		)
		(fp_line
			(start 0.120396 0.3048)
			(end 0.120396 0.2794)
			(stroke
				(width 0.1)
				(type default)
			)
			(layer "F.Fab")
		)
		(fp_line
			(start 0.120396 0.2794)
			(end -0.12065 0.2794)
			(stroke
				(width 0.1)
				(type default)
			)
			(layer "F.Fab")
		)
		(fp_line
			(start -0.12065 0.3048)
			(end -0.67945 0.3048)
			(stroke
				(width 0.1)
				(type default)
			)
			(layer "F.Fab")
		)
		(fp_line
			(start -0.12065 0.2794)
			(end -0.12065 0.3048)
			(stroke
				(width 0.1)
				(type default)
			)
			(layer "F.Fab")
		)
		(fp_line
			(start -0.12065 -0.2794)
			(end 0.12065 -0.2794)
			(stroke
				(width 0.1)
				(type default)
			)
			(layer "F.Fab")
		)
		(fp_line
			(start -0.12065 -0.305054)
			(end -0.12065 -0.2794)
			(stroke
				(width 0.1)
				(type default)
			)
			(layer "F.Fab")
		)
		(fp_line
			(start -0.67945 0.3048)
			(end -0.67945 -0.305054)
			(stroke
				(width 0.1)
				(type default)
			)
			(layer "F.Fab")
		)
		(fp_line
			(start -0.67945 -0.305054)
			(end -0.12065 -0.305054)
			(stroke
				(width 0.1)
				(type default)
			)
			(layer "F.Fab")
		)
		(pad "1" smd circle
			(at -0.40005 0 180)
			(size 0 0)
			(layers "F.Cu" "F.Mask" "F.Paste")
			(net "MB_FRU_ADDR1")
		)
		(pad "2" smd circle
			(at 0.40005 0 180)
			(size 0 0)
			(layers "F.Cu" "F.Mask" "F.Paste")
			(net "GND")
		)
	)
	(footprint ""
		(layer "F.Cu")
		(at 335.501488 -402.371052 -90)
		(property "Reference" "C1559"
			(at 0 0 270)
			(layer "F.SilkS")
			(hide yes)
			(effects
				(font
					(size 1.27 1.27)
				)
			)
		)
		(property "Value" ""
			(at 0 0 270)
			(layer "F.Fab")
			(effects
				(font
					(size 1.27 1.27)
				)
			)
		)
		(duplicate_pad_numbers_are_jumpers no)
		(fp_line
			(start -0.299974 0.150114)
			(end -0.299974 -0.150114)
			(stroke
				(width 0.1)
				(type default)
			)
			(layer "F.Fab")
		)
		(fp_line
			(start 0.299974 0.150114)
			(end -0.299974 0.150114)
			(stroke
				(width 0.1)
				(type default)
			)
			(layer "F.Fab")
		)
		(fp_line
			(start -0.299974 -0.150114)
			(end 0.299974 -0.150114)
			(stroke
				(width 0.1)
				(type default)
			)
			(layer "F.Fab")
		)
		(fp_line
			(start 0.299974 -0.150114)
			(end 0.299974 0.150114)
			(stroke
				(width 0.1)
				(type default)
			)
			(layer "F.Fab")
		)
		(pad "1" smd rect
			(at -0.2667 0 270)
			(size 0.3048 0.381)
			(layers "F.Cu" "F.Mask" "F.Paste")
			(net "P5E_CPU0_PE4_TX_C_DP<10>")
		)
		(pad "2" smd rect
			(at 0.2667 0 270)
			(size 0.3048 0.381)
			(layers "F.Cu" "F.Mask" "F.Paste")
			(net "P5E_CPU0_PE4_TX_DP<10>")
		)
	)
)
